# BASEBOARD_FAB2 (Tioga Pass) — schematic netlist excerpt (pin names and nets, part order shuffled) for the footprints in the layout excerpt that follows; sources: Cadence DE-HDL packaged netlist, KiCad conversion of Wiwynn_Tioga_Pass_MB.brd

J8G2  CONN12_C73564003  CONN  pkg PIP  page 135
  IO1  = TP_JUMPER_BLOCK_1_1
  IO2  = TP_JUMPER_BLOCK_1_2
  IO3  = RST_BMC_SRST_N
  IO4  = FM_IE_DISABLE_N
  IO5  = GND
  IO6  = GND
  IO7  = TP_JUMPER_BLOCK_1_7
  IO8  = TP_JUMPER_BLOCK_1_8
  IO9  = FM_CPLD_UART_CH_LOCK_N
  IO10  = FM_DIS_ADR_DLY
  IO11  = GND
  IO12  = GND

(kicad_pcb
	(version 20260206)
	(generator "pcbnew")
	(generator_version "10.0")
	(general
		(thickness 1.6)
		(legacy_teardrops no)
	)
	(paper "A4")
	(title_block
		(title "Wiwynn_Tioga_Pass_MB.brd")
		(comment 1 "Tioga Pass / footprint 1858 of 4770 (J8G2), pads 1-12 of 12")
	)
	(layers
		(0 "F.Cu" signal "TOP")
		(4 "In1.Cu" signal "L2GND")
		(6 "In2.Cu" signal "L3")
		(8 "In3.Cu" signal "L4GND")
		(10 "In4.Cu" signal "L5")
		(12 "In5.Cu" signal "L6GND")
		(14 "In6.Cu" signal "L7VCC")
		(16 "In7.Cu" signal "L8VCC")
		(18 "In8.Cu" signal "L9GND")
		(20 "In9.Cu" signal "L10")
		(22 "In10.Cu" signal "L11GND")
		(24 "In11.Cu" signal "L12")
		(26 "In12.Cu" signal "L13GND")
		(2 "B.Cu" signal "BOTTOM")
		(9 "F.Adhes" user "F.Adhesive")
		(11 "B.Adhes" user "B.Adhesive")
		(13 "F.Paste" user "Package Geometry/Pastemask Top")
		(15 "B.Paste" user "Package Geometry/Pastemask Bottom")
		(5 "F.SilkS" user "Ref Des/Silkscreen Top")
		(7 "B.SilkS" user "Ref Des/Silkscreen Bottom")
		(1 "F.Mask" user "Board Geometry/Soldermask Top")
		(3 "B.Mask" user "Board Geometry/Soldermask Bottom")
		(17 "Dwgs.User" user "User.Drawings")
		(19 "Cmts.User" user "User.Comments")
		(21 "Eco1.User" user "User.Eco1")
		(23 "Eco2.User" user "User.Eco2")
		(25 "Edge.Cuts" user "Board Geometry/Outline")
		(27 "Margin" user)
		(31 "F.CrtYd" user "Package Geometry/Place Bound Top")
		(29 "B.CrtYd" user "Package Geometry/Place Bound Bottom")
		(35 "F.Fab" user "Ref Des/Assembly Top")
		(33 "B.Fab" user "Ref Des/Assembly Bottom")
	)
	(footprint ""
		(layer "F.Cu")
		(at 432.689762 3.81 90)
		(property "Reference" "J8G2"
			(at 3.96621 6.19506 0)
			(unlocked yes)
			(layer "B.SilkS")
			(effects
				(font
					(size 0.7874 0.5842)
					(thickness 0.1524)
				)
				(justify mirror)
			)
		)
		(property "Value" ""
			(at 0 0 90)
			(layer "F.Fab")
			(effects
				(font
					(size 1.27 1.27)
				)
			)
		)
		(duplicate_pad_numbers_are_jumpers no)
		(pad "1" thru_hole rect
			(at 0 0 90)
			(size 1.6256 1.6256)
			(drill 1.2446)
			(layers "*.Cu" "*.Mask")
			(remove_unused_layers no)
			(net "TP_JUMPER_BLOCK_1_1")
			(clearance 0.127)
			(thermal_gap 0.127)
			(padstack
				(mode front_inner_back)
				(layer "Inner"
					(shape circle)
					(size 1.6256 1.6256)
					(clearance 0.127)
				)
				(layer "B.Cu"
					(shape rect)
					(size 1.6256 1.6256)
					(clearance 0.127)
				)
			)
		)
		(pad "2" thru_hole circle
			(at 2.54 0 90)
			(size 1.6256 1.6256)
			(drill 1.2446)
			(layers "*.Cu" "*.Mask")
			(remove_unused_layers no)
			(net "TP_JUMPER_BLOCK_1_2")
			(clearance 0.127)
			(thermal_gap 0.127)
		)
		(pad "3" thru_hole circle
			(at 0 2.54 90)
			(size 1.6256 1.6256)
			(drill 1.2446)
			(layers "*.Cu" "*.Mask")
			(remove_unused_layers no)
			(net "RST_BMC_SRST_N")
			(clearance 0.127)
			(thermal_gap 0.127)
		)
		(pad "4" thru_hole circle
			(at 2.54 2.54 90)
			(size 1.6256 1.6256)
			(drill 1.2446)
			(layers "*.Cu" "*.Mask")
			(remove_unused_layers no)
			(net "FM_IE_DISABLE_N")
			(clearance 0.127)
			(thermal_gap 0.127)
		)
		(pad "5" thru_hole circle
			(at 0 5.08 90)
			(size 1.6256 1.6256)
			(drill 1.2446)
			(layers "*.Cu" "*.Mask")
			(remove_unused_layers no)
			(net "GND")
			(clearance 0.127)
			(thermal_gap 0.127)
		)
		(pad "6" thru_hole circle
			(at 2.54 5.08 90)
			(size 1.6256 1.6256)
			(drill 1.2446)
			(layers "*.Cu" "*.Mask")
			(remove_unused_layers no)
			(net "GND")
			(clearance 0.127)
			(thermal_gap 0.127)
		)
		(pad "7" thru_hole circle
			(at 0 7.62 90)
			(size 1.6256 1.6256)
			(drill 1.2446)
			(layers "*.Cu" "*.Mask")
			(remove_unused_layers no)
			(net "TP_JUMPER_BLOCK_1_7")
			(clearance 0.127)
			(thermal_gap 0.127)
		)
		(pad "8" thru_hole circle
			(at 2.54 7.62 90)
			(size 1.6256 1.6256)
			(drill 1.2446)
			(layers "*.Cu" "*.Mask")
			(remove_unused_layers no)
			(net "TP_JUMPER_BLOCK_1_8")
			(clearance 0.127)
			(thermal_gap 0.127)
		)
		(pad "9" thru_hole circle
			(at 0 10.16 90)
			(size 1.6256 1.6256)
			(drill 1.2446)
			(layers "*.Cu" "*.Mask")
			(remove_unused_layers no)
			(net "FM_CPLD_UART_CH_LOCK_N")
			(clearance 0.127)
			(thermal_gap 0.127)
		)
		(pad "10" thru_hole circle
			(at 2.54 10.16 90)
			(size 1.6256 1.6256)
			(drill 1.2446)
			(layers "*.Cu" "*.Mask")
			(remove_unused_layers no)
			(net "FM_DIS_ADR_DLY")
			(clearance 0.127)
			(thermal_gap 0.127)
		)
		(pad "11" thru_hole circle
			(at 0 12.7 90)
			(size 1.6256 1.6256)
			(drill 1.2446)
			(layers "*.Cu" "*.Mask")
			(remove_unused_layers no)
			(net "GND")
			(clearance 0.127)
			(thermal_gap 0.127)
		)
		(pad "12" thru_hole circle
			(at 2.54 12.7 90)
			(size 1.6256 1.6256)
			(drill 1.2446)
			(layers "*.Cu" "*.Mask")
			(remove_unused_layers no)
			(net "GND")
			(clearance 0.127)
			(thermal_gap 0.127)
		)
	)
)
